(kicad_pcb
	(version 20260206)
	(generator "pcbnew")
	(generator_version "10.0")
	(general
		(thickness 1.6)
		(legacy_teardrops no)
	)
	(paper "A4")
	(title_block
		(title "04192023_DAF0TMB3IC0_F0TG_MB_C_brd_V02_OCP.brd")
		(comment 1 "Grand Teton / footprint 3955 of 8354 (U25), pads 5448-5557 of 6102")
	)
	(layers
		(0 "F.Cu" signal "TOP")
		(4 "In1.Cu" signal "GND")
		(6 "In2.Cu" signal "IN1")
		(8 "In3.Cu" signal "GND1")
		(10 "In4.Cu" signal "IN2")
		(12 "In5.Cu" signal "GND2")
		(14 "In6.Cu" signal "IN3")
		(16 "In7.Cu" signal "GND3")
		(18 "In8.Cu" signal "VCC")
		(20 "In9.Cu" signal "VCC1")
		(22 "In10.Cu" signal "GND4")
		(24 "In11.Cu" signal "IN4")
		(26 "In12.Cu" signal "GND5")
		(28 "In13.Cu" signal "IN5")
		(30 "In14.Cu" signal "GND6")
		(32 "In15.Cu" signal "IN6")
		(34 "In16.Cu" signal "GND7")
		(2 "B.Cu" signal "BOTTOM")
		(9 "F.Adhes" user "F.Adhesive")
		(11 "B.Adhes" user "B.Adhesive")
		(13 "F.Paste" user "Package Geometry/Pastemask Top")
		(15 "B.Paste" user "Package Geometry/Pastemask Bottom")
		(5 "F.SilkS" user "Ref Des/Silkscreen Top")
		(7 "B.SilkS" user "Ref Des/Silkscreen Bottom")
		(1 "F.Mask" user "Board Geometry/Soldermask Top")
		(3 "B.Mask" user "Board Geometry/Soldermask Bottom")
		(17 "Dwgs.User" user "User.Drawings")
		(19 "Cmts.User" user "User.Comments")
		(21 "Eco1.User" user "User.Eco1")
		(23 "Eco2.User" user "User.Eco2")
		(25 "Edge.Cuts" user "Board Geometry/Outline")
		(27 "Margin" user)
		(31 "F.CrtYd" user "Package Geometry/Place Bound Top")
		(29 "B.CrtYd" user "Package Geometry/Place Bound Bottom")
		(35 "F.Fab" user "Ref Des/Assembly Top")
		(33 "B.Fab" user "Ref Des/Assembly Bottom")
	)
	(footprint ""
		(layer "F.Cu")
		(at 359.867962 -258.880102 180)
		(property "Reference" "U25"
			(at -45.78477 -62.086744 0)
			(unlocked yes)
			(layer "F.SilkS")
			(effects
				(font
					(size 0.7874 0.5842)
					(thickness 0.1524)
				)
			)
		)
		(property "Value" ""
			(at 0 0 180)
			(layer "F.Fab")
			(effects
				(font
					(size 1.27 1.27)
				)
			)
		)
		(duplicate_pad_numbers_are_jumpers no)
		(pad "L69" smd circle
			(at 28.82011 -28.710128 180)
			(size 0.450088 0.450088)
			(layers "F.Cu" "F.Mask" "F.Paste")
			(net "M_E_CPU0_SA_DQ<7>")
		)
		(pad "L70" smd circle
			(at 29.75991 -28.710128 180)
			(size 0.450088 0.450088)
			(layers "F.Cu" "F.Mask" "F.Paste")
			(net "GND")
		)
		(pad "L71" smd circle
			(at 30.699964 -28.710128 180)
			(size 0.450088 0.450088)
			(layers "F.Cu" "F.Mask" "F.Paste")
			(net "M_E_CPU0_SA_DQ<8>")
		)
		(pad "L72" smd circle
			(at 31.640018 -28.710128 180)
			(size 0.450088 0.450088)
			(layers "F.Cu" "F.Mask" "F.Paste")
			(net "PVDDIO_P0")
		)
		(pad "L73" smd circle
			(at 32.580072 -28.710128 180)
			(size 0.450088 0.450088)
			(layers "F.Cu" "F.Mask" "F.Paste")
			(net "M_A_CPU0_SA_DQ<7>")
		)
		(pad "L74" smd circle
			(at 33.519872 -28.710128 180)
			(size 0.450088 0.450088)
			(layers "F.Cu" "F.Mask" "F.Paste")
			(net "M_A_CPU0_SA_DQ<8>")
		)
		(pad "L75" smd circle
			(at 34.459926 -28.710128 180)
			(size 0.450088 0.450088)
			(layers "F.Cu" "F.Mask" "F.Paste")
			(net "GND")
		)
		(pad "M2" smd circle
			(at -33.690052 -27.900122 180)
			(size 0.450088 0.450088)
			(layers "F.Cu" "F.Mask" "F.Paste")
			(net "M_G_CPU0_SA_DQ<10>")
		)
		(pad "M3" smd circle
			(at -32.749998 -27.900122 180)
			(size 0.450088 0.450088)
			(layers "F.Cu" "F.Mask" "F.Paste")
			(net "GND")
		)
		(pad "M4" smd circle
			(at -31.809944 -27.900122 180)
			(size 0.450088 0.450088)
			(layers "F.Cu" "F.Mask" "F.Paste")
			(net "M_G_CPU0_SA_DQ<9>")
		)
		(pad "M5" smd circle
			(at -30.86989 -27.900122 180)
			(size 0.450088 0.450088)
			(layers "F.Cu" "F.Mask" "F.Paste")
			(net "GND")
		)
		(pad "M6" smd circle
			(at -29.93009 -27.900122 180)
			(size 0.450088 0.450088)
			(layers "F.Cu" "F.Mask" "F.Paste")
			(net "M_K_CPU0_SA_DQ<10>")
		)
		(pad "M7" smd circle
			(at -28.990036 -27.900122 180)
			(size 0.450088 0.450088)
			(layers "F.Cu" "F.Mask" "F.Paste")
			(net "M_K_CPU0_SA_DQ<9>")
		)
		(pad "M8" smd circle
			(at -28.049982 -27.900122 180)
			(size 0.450088 0.450088)
			(layers "F.Cu" "F.Mask" "F.Paste")
			(net "GND")
		)
		(pad "M9" smd circle
			(at -27.109928 -27.900122 180)
			(size 0.450088 0.450088)
			(layers "F.Cu" "F.Mask" "F.Paste")
			(net "M_L_CPU0_SA_DQ<10>")
		)
		(pad "M10" smd circle
			(at -26.170128 -27.900122 180)
			(size 0.450088 0.450088)
			(layers "F.Cu" "F.Mask" "F.Paste")
			(net "GND")
		)
		(pad "M11" smd circle
			(at -25.230074 -27.900122 180)
			(size 0.450088 0.450088)
			(layers "F.Cu" "F.Mask" "F.Paste")
			(net "M_L_CPU0_SA_DQ<9>")
		)
		(pad "M12" smd circle
			(at -24.29002 -27.900122 180)
			(size 0.450088 0.450088)
			(layers "F.Cu" "F.Mask" "F.Paste")
			(net "GND")
		)
		(pad "M13" smd circle
			(at -23.349966 -27.900122 180)
			(size 0.450088 0.450088)
			(layers "F.Cu" "F.Mask" "F.Paste")
			(net "M_H_CPU0_SA_DQ<10>")
		)
		(pad "M14" smd circle
			(at -22.409912 -27.900122 180)
			(size 0.450088 0.450088)
			(layers "F.Cu" "F.Mask" "F.Paste")
			(net "M_H_CPU0_SA_DQ<9>")
		)
		(pad "M15" smd circle
			(at -21.470112 -27.900122 180)
			(size 0.450088 0.450088)
			(layers "F.Cu" "F.Mask" "F.Paste")
			(net "GND")
		)
		(pad "M16" smd circle
			(at -20.530058 -27.900122 180)
			(size 0.450088 0.450088)
			(layers "F.Cu" "F.Mask" "F.Paste")
			(net "M_J_CPU0_SA_DQ<10>")
		)
		(pad "M17" smd circle
			(at -19.590004 -27.900122 180)
			(size 0.450088 0.450088)
			(layers "F.Cu" "F.Mask" "F.Paste")
			(net "GND")
		)
		(pad "M18" smd circle
			(at -18.64995 -27.900122 180)
			(size 0.450088 0.450088)
			(layers "F.Cu" "F.Mask" "F.Paste")
			(net "M_J_CPU0_SA_DQ<9>")
		)
		(pad "M19" smd circle
			(at -17.709896 -27.900122 180)
			(size 0.450088 0.450088)
			(layers "F.Cu" "F.Mask" "F.Paste")
			(net "GND")
		)
		(pad "M20" smd circle
			(at -16.770096 -27.900122 180)
			(size 0.450088 0.450088)
			(layers "F.Cu" "F.Mask" "F.Paste")
			(net "M_I_CPU0_SA_DQ<10>")
		)
		(pad "M21" smd circle
			(at -15.830042 -27.900122 180)
			(size 0.450088 0.450088)
			(layers "F.Cu" "F.Mask" "F.Paste")
			(net "M_I_CPU0_SA_DQ<9>")
		)
		(pad "M22" smd circle
			(at -14.889988 -27.900122 180)
			(size 0.450088 0.450088)
			(layers "F.Cu" "F.Mask" "F.Paste")
			(net "GND")
		)
		(pad "M23" smd circle
			(at -13.949934 -27.900122 180)
			(size 0.450088 0.450088)
			(layers "F.Cu" "F.Mask" "F.Paste")
			(net "PVDDCR_CPU0_P0")
		)
		(pad "M24" smd circle
			(at -13.00988 -27.900122 180)
			(size 0.450088 0.450088)
			(layers "F.Cu" "F.Mask" "F.Paste")
			(net "PVDDCR_CPU0_P0")
		)
		(pad "M25" smd circle
			(at -12.07008 -27.900122 180)
			(size 0.450088 0.450088)
			(layers "F.Cu" "F.Mask" "F.Paste")
			(net "GND")
		)
		(pad "M26" smd circle
			(at -11.130026 -27.900122 180)
			(size 0.450088 0.450088)
			(layers "F.Cu" "F.Mask" "F.Paste")
			(net "PVDDCR_CPU0_P0")
		)
		(pad "M27" smd circle
			(at -10.189972 -27.900122 180)
			(size 0.450088 0.450088)
			(layers "F.Cu" "F.Mask" "F.Paste")
			(net "PVDDCR_CPU0_P0")
		)
		(pad "M28" smd circle
			(at -9.249918 -27.900122 180)
			(size 0.450088 0.450088)
			(layers "F.Cu" "F.Mask" "F.Paste")
			(net "GND")
		)
		(pad "M29" smd circle
			(at -8.310118 -27.900122 180)
			(size 0.450088 0.450088)
			(layers "F.Cu" "F.Mask" "F.Paste")
			(net "PVDDCR_CPU0_P0")
		)
		(pad "M30" smd circle
			(at -7.370064 -27.900122 180)
			(size 0.450088 0.450088)
			(layers "F.Cu" "F.Mask" "F.Paste")
			(net "PVDDCR_CPU0_P0")
		)
		(pad "M31" smd circle
			(at -6.43001 -27.900122 180)
			(size 0.450088 0.450088)
			(layers "F.Cu" "F.Mask" "F.Paste")
			(net "GND")
		)
		(pad "M32" smd circle
			(at -5.489956 -27.900122 180)
			(size 0.450088 0.450088)
			(layers "F.Cu" "F.Mask" "F.Paste")
			(net "PVDDCR_CPU0_P0")
		)
		(pad "M33" smd circle
			(at -4.549902 -27.900122 180)
			(size 0.450088 0.450088)
			(layers "F.Cu" "F.Mask" "F.Paste")
			(net "PVDDCR_CPU0_P0")
		)
		(pad "M34" smd circle
			(at -3.610102 -27.900122 180)
			(size 0.450088 0.450088)
			(layers "F.Cu" "F.Mask" "F.Paste")
			(net "GND")
		)
		(pad "M35" smd circle
			(at -2.670048 -27.900122 180)
			(size 0.450088 0.450088)
			(layers "F.Cu" "F.Mask" "F.Paste")
			(net "GMI_CPU0_G2_CPU1_G0_TX_DP<15>")
		)
		(pad "M36" smd circle
			(at -1.729994 -27.900122 180)
			(size 0.450088 0.450088)
			(layers "F.Cu" "F.Mask" "F.Paste")
			(net "GMI_CPU0_G2_CPU1_G0_TX_DN<15>")
		)
		(pad "M37" smd circle
			(at -0.78994 -27.900122 180)
			(size 0.450088 0.450088)
			(layers "F.Cu" "F.Mask" "F.Paste")
			(net "GND")
		)
		(pad "M39" smd circle
			(at 1.089914 -27.900122 180)
			(size 0.450088 0.450088)
			(layers "F.Cu" "F.Mask" "F.Paste")
			(net "GND")
		)
		(pad "M40" smd circle
			(at 2.029968 -27.900122 180)
			(size 0.450088 0.450088)
			(layers "F.Cu" "F.Mask" "F.Paste")
			(net "GMI_CPU1_G2_CPU0_G0_TX_DN<0>")
		)
		(pad "M41" smd circle
			(at 2.970022 -27.900122 180)
			(size 0.450088 0.450088)
			(layers "F.Cu" "F.Mask" "F.Paste")
			(net "GMI_CPU1_G2_CPU0_G0_TX_DP<0>")
		)
		(pad "M42" smd circle
			(at 3.910076 -27.900122 180)
			(size 0.450088 0.450088)
			(layers "F.Cu" "F.Mask" "F.Paste")
			(net "GND")
		)
		(pad "M43" smd circle
			(at 4.849876 -27.900122 180)
			(size 0.450088 0.450088)
			(layers "F.Cu" "F.Mask" "F.Paste")
			(net "PVDDCR_CPU0_P0")
		)
		(pad "M44" smd circle
			(at 5.78993 -27.900122 180)
			(size 0.450088 0.450088)
			(layers "F.Cu" "F.Mask" "F.Paste")
			(net "PVDDCR_CPU0_P0")
		)
		(pad "M45" smd circle
			(at 6.729984 -27.900122 180)
			(size 0.450088 0.450088)
			(layers "F.Cu" "F.Mask" "F.Paste")
			(net "GND")
		)
		(pad "M46" smd circle
			(at 7.670038 -27.900122 180)
			(size 0.450088 0.450088)
			(layers "F.Cu" "F.Mask" "F.Paste")
			(net "PVDDCR_CPU0_P0")
		)
		(pad "M47" smd circle
			(at 8.610092 -27.900122 180)
			(size 0.450088 0.450088)
			(layers "F.Cu" "F.Mask" "F.Paste")
			(net "PVDDCR_CPU0_P0")
		)
		(pad "M48" smd circle
			(at 9.549892 -27.900122 180)
			(size 0.450088 0.450088)
			(layers "F.Cu" "F.Mask" "F.Paste")
			(net "GND")
		)
		(pad "M49" smd circle
			(at 10.489946 -27.900122 180)
			(size 0.450088 0.450088)
			(layers "F.Cu" "F.Mask" "F.Paste")
			(net "PVDDCR_CPU0_P0")
		)
		(pad "M50" smd circle
			(at 11.43 -27.900122 180)
			(size 0.450088 0.450088)
			(layers "F.Cu" "F.Mask" "F.Paste")
			(net "PVDDCR_CPU0_P0")
		)
		(pad "M51" smd circle
			(at 12.370054 -27.900122 180)
			(size 0.450088 0.450088)
			(layers "F.Cu" "F.Mask" "F.Paste")
			(net "GND")
		)
		(pad "M52" smd circle
			(at 13.310108 -27.900122 180)
			(size 0.450088 0.450088)
			(layers "F.Cu" "F.Mask" "F.Paste")
			(net "PVDDCR_CPU0_P0")
		)
		(pad "M53" smd circle
			(at 14.249908 -27.900122 180)
			(size 0.450088 0.450088)
			(layers "F.Cu" "F.Mask" "F.Paste")
			(net "PVDDCR_CPU0_P0")
		)
		(pad "M54" smd circle
			(at 15.189962 -27.900122 180)
			(size 0.450088 0.450088)
			(layers "F.Cu" "F.Mask" "F.Paste")
			(net "GND")
		)
		(pad "M55" smd circle
			(at 16.130016 -27.900122 180)
			(size 0.450088 0.450088)
			(layers "F.Cu" "F.Mask" "F.Paste")
			(net "M_C_CPU0_SA_DQ<9>")
		)
		(pad "M56" smd circle
			(at 17.07007 -27.900122 180)
			(size 0.450088 0.450088)
			(layers "F.Cu" "F.Mask" "F.Paste")
			(net "M_C_CPU0_SA_DQ<10>")
		)
		(pad "M57" smd circle
			(at 18.010124 -27.900122 180)
			(size 0.450088 0.450088)
			(layers "F.Cu" "F.Mask" "F.Paste")
			(net "GND")
		)
		(pad "M58" smd circle
			(at 18.949924 -27.900122 180)
			(size 0.450088 0.450088)
			(layers "F.Cu" "F.Mask" "F.Paste")
			(net "M_D_CPU0_SA_DQ<9>")
		)
		(pad "M59" smd circle
			(at 19.889978 -27.900122 180)
			(size 0.450088 0.450088)
			(layers "F.Cu" "F.Mask" "F.Paste")
			(net "GND")
		)
		(pad "M60" smd circle
			(at 20.830032 -27.900122 180)
			(size 0.450088 0.450088)
			(layers "F.Cu" "F.Mask" "F.Paste")
			(net "M_D_CPU0_SA_DQ<10>")
		)
		(pad "M61" smd circle
			(at 21.770086 -27.900122 180)
			(size 0.450088 0.450088)
			(layers "F.Cu" "F.Mask" "F.Paste")
			(net "GND")
		)
		(pad "M62" smd circle
			(at 22.709886 -27.900122 180)
			(size 0.450088 0.450088)
			(layers "F.Cu" "F.Mask" "F.Paste")
			(net "M_B_CPU0_SA_DQ<9>")
		)
		(pad "M63" smd circle
			(at 23.64994 -27.900122 180)
			(size 0.450088 0.450088)
			(layers "F.Cu" "F.Mask" "F.Paste")
			(net "M_B_CPU0_SA_DQ<10>")
		)
		(pad "M64" smd circle
			(at 24.589994 -27.900122 180)
			(size 0.450088 0.450088)
			(layers "F.Cu" "F.Mask" "F.Paste")
			(net "GND")
		)
		(pad "M65" smd circle
			(at 25.530048 -27.900122 180)
			(size 0.450088 0.450088)
			(layers "F.Cu" "F.Mask" "F.Paste")
			(net "M_F_CPU0_SA_DQ<9>")
		)
		(pad "M66" smd circle
			(at 26.470102 -27.900122 180)
			(size 0.450088 0.450088)
			(layers "F.Cu" "F.Mask" "F.Paste")
			(net "GND")
		)
		(pad "M67" smd circle
			(at 27.409902 -27.900122 180)
			(size 0.450088 0.450088)
			(layers "F.Cu" "F.Mask" "F.Paste")
			(net "M_F_CPU0_SA_DQ<10>")
		)
		(pad "M68" smd circle
			(at 28.349956 -27.900122 180)
			(size 0.450088 0.450088)
			(layers "F.Cu" "F.Mask" "F.Paste")
			(net "GND")
		)
		(pad "M69" smd circle
			(at 29.29001 -27.900122 180)
			(size 0.450088 0.450088)
			(layers "F.Cu" "F.Mask" "F.Paste")
			(net "M_E_CPU0_SA_DQ<9>")
		)
		(pad "M70" smd circle
			(at 30.230064 -27.900122 180)
			(size 0.450088 0.450088)
			(layers "F.Cu" "F.Mask" "F.Paste")
			(net "M_E_CPU0_SA_DQ<10>")
		)
		(pad "M71" smd circle
			(at 31.170118 -27.900122 180)
			(size 0.450088 0.450088)
			(layers "F.Cu" "F.Mask" "F.Paste")
			(net "GND")
		)
		(pad "M72" smd circle
			(at 32.109918 -27.900122 180)
			(size 0.450088 0.450088)
			(layers "F.Cu" "F.Mask" "F.Paste")
			(net "M_A_CPU0_SA_DQ<9>")
		)
		(pad "M73" smd circle
			(at 33.049972 -27.900122 180)
			(size 0.450088 0.450088)
			(layers "F.Cu" "F.Mask" "F.Paste")
			(net "GND")
		)
		(pad "M74" smd circle
			(at 33.990026 -27.900122 180)
			(size 0.450088 0.450088)
			(layers "F.Cu" "F.Mask" "F.Paste")
			(net "M_A_CPU0_SA_DQ<10>")
		)
		(pad "N1" smd circle
			(at -34.159952 -27.090116 180)
			(size 0.450088 0.450088)
			(layers "F.Cu" "F.Mask" "F.Paste")
			(net "GND")
		)
		(pad "N2" smd circle
			(at -33.219898 -27.090116 180)
			(size 0.450088 0.450088)
			(layers "F.Cu" "F.Mask" "F.Paste")
			(net "M_G_CPU0_SA_DQS_DP<1>")
		)
		(pad "N3" smd circle
			(at -32.280098 -27.090116 180)
			(size 0.450088 0.450088)
			(layers "F.Cu" "F.Mask" "F.Paste")
			(net "M_G_CPU0_SA_DQ<11>")
		)
		(pad "N4" smd circle
			(at -31.340044 -27.090116 180)
			(size 0.450088 0.450088)
			(layers "F.Cu" "F.Mask" "F.Paste")
			(net "GND")
		)
		(pad "N5" smd circle
			(at -30.39999 -27.090116 180)
			(size 0.450088 0.450088)
			(layers "F.Cu" "F.Mask" "F.Paste")
			(net "M_K_CPU0_SA_DQS_DP<1>")
		)
		(pad "N6" smd circle
			(at -29.459936 -27.090116 180)
			(size 0.450088 0.450088)
			(layers "F.Cu" "F.Mask" "F.Paste")
			(net "GND")
		)
		(pad "N7" smd circle
			(at -28.519882 -27.090116 180)
			(size 0.450088 0.450088)
			(layers "F.Cu" "F.Mask" "F.Paste")
			(net "M_K_CPU0_SA_DQ<11>")
		)
		(pad "N8" smd circle
			(at -27.580082 -27.090116 180)
			(size 0.450088 0.450088)
			(layers "F.Cu" "F.Mask" "F.Paste")
			(net "GND")
		)
		(pad "N9" smd circle
			(at -26.640028 -27.090116 180)
			(size 0.450088 0.450088)
			(layers "F.Cu" "F.Mask" "F.Paste")
			(net "M_L_CPU0_SA_DQS_DP<1>")
		)
		(pad "N10" smd circle
			(at -25.699974 -27.090116 180)
			(size 0.450088 0.450088)
			(layers "F.Cu" "F.Mask" "F.Paste")
			(net "M_L_CPU0_SA_DQ<11>")
		)
		(pad "N11" smd circle
			(at -24.75992 -27.090116 180)
			(size 0.450088 0.450088)
			(layers "F.Cu" "F.Mask" "F.Paste")
			(net "GND")
		)
		(pad "N12" smd circle
			(at -23.82012 -27.090116 180)
			(size 0.450088 0.450088)
			(layers "F.Cu" "F.Mask" "F.Paste")
			(net "M_H_CPU0_SA_DQS_DP<1>")
		)
		(pad "N13" smd circle
			(at -22.880066 -27.090116 180)
			(size 0.450088 0.450088)
			(layers "F.Cu" "F.Mask" "F.Paste")
			(net "GND")
		)
		(pad "N14" smd circle
			(at -21.940012 -27.090116 180)
			(size 0.450088 0.450088)
			(layers "F.Cu" "F.Mask" "F.Paste")
			(net "M_H_CPU0_SA_DQ<11>")
		)
		(pad "N15" smd circle
			(at -20.999958 -27.090116 180)
			(size 0.450088 0.450088)
			(layers "F.Cu" "F.Mask" "F.Paste")
			(net "GND")
		)
		(pad "N16" smd circle
			(at -20.059904 -27.090116 180)
			(size 0.450088 0.450088)
			(layers "F.Cu" "F.Mask" "F.Paste")
			(net "M_J_CPU0_SA_DQS_DP<1>")
		)
		(pad "N17" smd circle
			(at -19.120104 -27.090116 180)
			(size 0.450088 0.450088)
			(layers "F.Cu" "F.Mask" "F.Paste")
			(net "M_J_CPU0_SA_DQ<11>")
		)
		(pad "N18" smd circle
			(at -18.18005 -27.090116 180)
			(size 0.450088 0.450088)
			(layers "F.Cu" "F.Mask" "F.Paste")
			(net "GND")
		)
		(pad "N19" smd circle
			(at -17.239996 -27.090116 180)
			(size 0.450088 0.450088)
			(layers "F.Cu" "F.Mask" "F.Paste")
			(net "M_I_CPU0_SA_DQS_DP<1>")
		)
		(pad "N20" smd circle
			(at -16.299942 -27.090116 180)
			(size 0.450088 0.450088)
			(layers "F.Cu" "F.Mask" "F.Paste")
			(net "GND")
		)
		(pad "N21" smd circle
			(at -15.359888 -27.090116 180)
			(size 0.450088 0.450088)
			(layers "F.Cu" "F.Mask" "F.Paste")
			(net "M_I_CPU0_SA_DQ<11>")
		)
		(pad "N22" smd circle
			(at -14.420088 -27.090116 180)
			(size 0.450088 0.450088)
			(layers "F.Cu" "F.Mask" "F.Paste")
			(net "GND")
		)
		(pad "N23" smd circle
			(at -13.480034 -27.090116 180)
			(size 0.450088 0.450088)
			(layers "F.Cu" "F.Mask" "F.Paste")
			(net "GMI_CPU0_G2_CPU1_G0_TX_DP<0>")
		)
		(pad "N24" smd circle
			(at -12.53998 -27.090116 180)
			(size 0.450088 0.450088)
			(layers "F.Cu" "F.Mask" "F.Paste")
			(net "GMI_CPU0_G2_CPU1_G0_TX_DN<0>")
		)
		(pad "N25" smd circle
			(at -11.599926 -27.090116 180)
			(size 0.450088 0.450088)
			(layers "F.Cu" "F.Mask" "F.Paste")
			(net "GND")
		)
		(pad "N26" smd circle
			(at -10.659872 -27.090116 180)
			(size 0.450088 0.450088)
			(layers "F.Cu" "F.Mask" "F.Paste")
			(net "P5E_CPU0_G3_TX_DP<5>")
		)
		(pad "N27" smd circle
			(at -9.720072 -27.090116 180)
			(size 0.450088 0.450088)
			(layers "F.Cu" "F.Mask" "F.Paste")
			(net "P5E_CPU0_G3_TX_DN<5>")
		)
		(pad "N28" smd circle
			(at -8.780018 -27.090116 180)
			(size 0.450088 0.450088)
			(layers "F.Cu" "F.Mask" "F.Paste")
			(net "GND")
		)
		(pad "N29" smd circle
			(at -7.839964 -27.090116 180)
			(size 0.450088 0.450088)
			(layers "F.Cu" "F.Mask" "F.Paste")
			(net "P5E_CPU0_G3_TX_DP<8>")
		)
		(pad "N30" smd circle
			(at -6.89991 -27.090116 180)
			(size 0.450088 0.450088)
			(layers "F.Cu" "F.Mask" "F.Paste")
			(net "P5E_CPU0_G3_TX_DN<8>")
		)
		(pad "N31" smd circle
			(at -5.96011 -27.090116 180)
			(size 0.450088 0.450088)
			(layers "F.Cu" "F.Mask" "F.Paste")
			(net "GND")
		)
	)
)
